(kicad_pcb
	(version 20241229)
	(generator "pcbnew")
	(generator_version "9.0")
	(general
		(thickness 1.711)
		(legacy_teardrops no)
	)
	(paper "A4")
	(title_block
		(title "Antmicro Baseboard for Jetson AGX Thor")
		(date "2026-02-18")
		(rev "1.1.0")
		(company "Antmicro Ltd")
		(comment 1 "www.antmicro.com")
		(comment 9 "footprints 454-457 of 1170")
	)
	(layers
		(0 "F.Cu" signal)
		(4 "In1.Cu" signal)
		(6 "In2.Cu" signal)
		(8 "In3.Cu" signal)
		(10 "In4.Cu" jumper)
		(12 "In5.Cu" signal)
		(14 "In6.Cu" signal)
		(16 "In7.Cu" signal)
		(18 "In8.Cu" signal)
		(2 "B.Cu" signal)
		(9 "F.Adhes" user "F.Adhesive")
		(11 "B.Adhes" user "B.Adhesive")
		(13 "F.Paste" user)
		(15 "B.Paste" user)
		(5 "F.SilkS" user "F.Silkscreen")
		(7 "B.SilkS" user "B.Silkscreen")
		(1 "F.Mask" user)
		(3 "B.Mask" user)
		(17 "Dwgs.User" user "User.Drawings")
		(19 "Cmts.User" user "User.Comments")
		(21 "Eco1.User" user "User.Eco1")
		(23 "Eco2.User" user "User.Eco2")
		(25 "Edge.Cuts" user)
		(27 "Margin" user)
		(31 "F.CrtYd" user "F.Courtyard")
		(29 "B.CrtYd" user "B.Courtyard")
		(35 "F.Fab" user)
		(33 "B.Fab" user)
	)
	(footprint "antmicro-footprints:XSON-8_1x1.95mm_P0.5mm"
		(layer "F.Cu")
		(at 65.6 97.2 180)
		(property "Reference" "U48"
			(at 1.2 1.4 180)
			(layer "F.SilkS")
			(effects
				(font
					(size 0.7 0.7)
					(thickness 0.15)
				)
				(justify left bottom)
			)
		)
		(property "Value" "NTS0102_XSON"
			(at 0 2.2 180)
			(layer "F.Fab")
			(effects
				(font
					(size 0.7 0.7)
					(thickness 0.15)
				)
				(justify left bottom)
			)
		)
		(property "Datasheet" "http://www.farnell.com/datasheets/1760723.pdf"
			(at 0 0 180)
			(layer "F.Fab")
			(hide yes)
			(effects
				(font
					(size 1.27 1.27)
					(thickness 0.15)
				)
			)
		)
		(property "Description" "Transceiver, 1.65 V to 3.6 V, XSON-8"
			(at 0 0 180)
			(layer "F.Fab")
			(hide yes)
			(effects
				(font
					(size 1.27 1.27)
					(thickness 0.15)
				)
			)
		)
		(property "MPN" "NTS0102GT"
			(at 0 0 180)
			(unlocked yes)
			(layer "F.Fab")
			(hide yes)
			(effects
				(font
					(size 1 1)
					(thickness 0.15)
				)
			)
		)
		(property "Manufacturer" "NXP"
			(at 0 0 180)
			(unlocked yes)
			(layer "F.Fab")
			(hide yes)
			(effects
				(font
					(size 1 1)
					(thickness 0.15)
				)
			)
		)
		(property "Author" "Antmicro"
			(at 0 0 180)
			(unlocked yes)
			(layer "F.Fab")
			(hide yes)
			(effects
				(font
					(size 1 1)
					(thickness 0.15)
				)
			)
		)
		(property "License" "Apache-2.0"
			(at 0 0 180)
			(unlocked yes)
			(layer "F.Fab")
			(hide yes)
			(effects
				(font
					(size 1 1)
					(thickness 0.15)
				)
			)
		)
		(sheetname "/CSI/")
		(sheetfile "csi.kicad_sch")
		(attr smd)
		(fp_line
			(start 0.5 1.1)
			(end -0.5 1.1)
			(stroke
				(width 0.15)
				(type solid)
			)
			(layer "F.SilkS")
		)
		(fp_line
			(start -0.5 -1.1)
			(end 0.5 -1.1)
			(stroke
				(width 0.15)
				(type solid)
			)
			(layer "F.SilkS")
		)
		(fp_circle
			(center -0.75 -1.1)
			(end -0.701 -1.1)
			(stroke
				(width 0.15)
				(type solid)
			)
			(fill no)
			(layer "F.SilkS")
		)
		(fp_rect
			(start -0.8 -1.2)
			(end 0.8 1.2)
			(stroke
				(width 0.05)
				(type solid)
			)
			(fill no)
			(layer "F.CrtYd")
		)
		(fp_line
			(start 0.5305 1)
			(end -0.5305 1)
			(stroke
				(width 0.15)
				(type solid)
			)
			(layer "F.Fab")
		)
		(fp_line
			(start 0.5305 -1.001)
			(end 0.5305 1)
			(stroke
				(width 0.15)
				(type solid)
			)
			(layer "F.Fab")
		)
		(fp_line
			(start -0.5305 1)
			(end -0.5305 -1.001)
			(stroke
				(width 0.15)
				(type solid)
			)
			(layer "F.Fab")
		)
		(fp_line
			(start -0.5305 -1.001)
			(end 0.5305 -1.001)
			(stroke
				(width 0.15)
				(type solid)
			)
			(layer "F.Fab")
		)
		(fp_text user "License: Apache-2.0"
			(at -0.527 8.306 180)
			(layer "F.Fab")
			(effects
				(font
					(size 0.7 0.7)
					(thickness 0.15)
				)
				(justify left bottom)
			)
		)
		(fp_text user "Author: Antmicro"
			(at -0.527 7.105 180)
			(layer "F.Fab")
			(effects
				(font
					(size 0.7 0.7)
					(thickness 0.15)
				)
				(justify left bottom)
			)
		)
		(fp_text user "${REFERENCE}"
			(at -0.527 5.905 180)
			(layer "F.Fab")
			(effects
				(font
					(size 0.7 0.7)
					(thickness 0.15)
				)
				(justify left bottom)
			)
		)
		(pad "1" smd roundrect
			(at -0.45 -0.75)
			(size 0.6 0.3)
			(layers "F.Cu" "F.Mask" "F.Paste")
			(roundrect_rratio 0.25)
			(net 194 "/CSI/VSYNC_CAM1_3V3")
			(pinfunction "B_{2}")
			(pintype "bidirectional")
		)
		(pad "2" smd roundrect
			(at -0.45 -0.25)
			(size 0.6 0.25)
			(layers "F.Cu" "F.Mask" "F.Paste")
			(roundrect_rratio 0.25)
			(net 1 "GND")
			(pinfunction "GND")
			(pintype "power_in")
		)
		(pad "3" smd roundrect
			(at -0.45 0.25)
			(size 0.6 0.25)
			(layers "F.Cu" "F.Mask" "F.Paste")
			(roundrect_rratio 0.25)
			(net 11 "+1V8")
			(pinfunction "VCC_{A}")
			(pintype "power_in")
		)
		(pad "4" smd roundrect
			(at -0.45 0.75)
			(size 0.6 0.3)
			(layers "F.Cu" "F.Mask" "F.Paste")
			(roundrect_rratio 0.25)
			(net 131 "/CSI/CAM_CTRL.VSYNC_CAM1")
			(pinfunction "A_{2}")
			(pintype "bidirectional")
		)
		(pad "5" smd roundrect
			(at 0.45 0.75)
			(size 0.6 0.3)
			(layers "F.Cu" "F.Mask" "F.Paste")
			(roundrect_rratio 0.25)
			(net 155 "/CSI/CAM_CTRL.VSYNC_CAM0")
			(pinfunction "A_{1}")
			(pintype "bidirectional")
		)
		(pad "6" smd roundrect
			(at 0.45 0.25)
			(size 0.6 0.25)
			(layers "F.Cu" "F.Mask" "F.Paste")
			(roundrect_rratio 0.25)
			(net 11 "+1V8")
			(pinfunction "OE")
			(pintype "input")
		)
		(pad "7" smd roundrect
			(at 0.45 -0.25)
			(size 0.6 0.25)
			(layers "F.Cu" "F.Mask" "F.Paste")
			(roundrect_rratio 0.25)
			(net 2 "+3V3")
			(pinfunction "VCC_{B}")
			(pintype "power_in")
		)
		(pad "8" smd roundrect
			(at 0.45 -0.75)
			(size 0.6 0.3)
			(layers "F.Cu" "F.Mask" "F.Paste")
			(roundrect_rratio 0.25)
			(net 186 "/CSI/VSYNC_CAM0_3V3")
			(pinfunction "B_{1}")
			(pintype "bidirectional")
		)
	)
	(footprint "antmicro-footprints:TP_SMD_0.75mm"
		(layer "F.Cu")
		(at 202.1 73.45 -90)
		(property "Reference" "TP10"
			(at -3.35 0.1 90)
			(layer "F.SilkS")
			(effects
				(font
					(size 0.7 0.7)
					(thickness 0.15)
				)
				(justify right top)
			)
		)
		(property "Value" "TP_0.75mm_SMD"
			(at 0 1.2 90)
			(layer "F.Fab")
			(effects
				(font
					(size 0.7 0.7)
					(thickness 0.15)
				)
				(justify right top)
			)
		)
		(property "Description" "SMT test point"
			(at 0 0 90)
			(layer "F.Fab")
			(hide yes)
			(effects
				(font
					(size 1.27 1.27)
					(thickness 0.15)
				)
			)
		)
		(property "MPN" ""
			(at 0 0 270)
			(unlocked yes)
			(layer "F.Fab")
			(hide yes)
			(effects
				(font
					(size 1 1)
					(thickness 0.15)
				)
			)
		)
		(property "Manufacturer" ""
			(at 0 0 270)
			(unlocked yes)
			(layer "F.Fab")
			(hide yes)
			(effects
				(font
					(size 1 1)
					(thickness 0.15)
				)
			)
		)
		(property "Author" "Antmicro"
			(at 0 0 270)
			(unlocked yes)
			(layer "F.Fab")
			(hide yes)
			(effects
				(font
					(size 1 1)
					(thickness 0.15)
				)
			)
		)
		(property "License" "Apache-2.0"
			(at 0 0 270)
			(unlocked yes)
			(layer "F.Fab")
			(hide yes)
			(effects
				(font
					(size 1 1)
					(thickness 0.15)
				)
			)
		)
		(sheetname "/USB Debug, PD/")
		(sheetfile "usb_debug_pd.kicad_sch")
		(attr exclude_from_pos_files exclude_from_bom)
		(fp_circle
			(center 0 0)
			(end 0.475 0)
			(stroke
				(width 0.05)
				(type default)
			)
			(fill no)
			(layer "F.CrtYd")
		)
		(fp_text user "${REFERENCE}"
			(at -0.4 2.7 90)
			(layer "F.Fab")
			(effects
				(font
					(size 0.7 0.7)
					(thickness 0.15)
				)
				(justify right top)
			)
		)
		(fp_text user "License: Apache-2.0"
			(at -0.4 5.101 90)
			(layer "F.Fab")
			(effects
				(font
					(size 0.7 0.7)
					(thickness 0.15)
				)
				(justify right top)
			)
		)
		(fp_text user "Author: Antmicro"
			(at -0.4 3.901 90)
			(layer "F.Fab")
			(effects
				(font
					(size 0.7 0.7)
					(thickness 0.15)
				)
				(justify right top)
			)
		)
		(pad "1" smd circle
			(at 0 0 270)
			(size 0.75 0.75)
			(layers "F.Cu" "F.Mask")
			(net 1039 "/USB Debug, PD/PDC_I2C3_SCL")
			(pinfunction "1")
			(pintype "passive")
		)
	)
	(footprint "antmicro-footprints:L_Bourns-SRP7028A"
		(layer "F.Cu")
		(at 120.12 59.28 90)
		(property "Reference" "L8"
			(at 3.71 2.27 180)
			(layer "F.SilkS")
			(effects
				(font
					(size 0.7 0.7)
					(thickness 0.15)
				)
				(justify left bottom)
			)
		)
		(property "Value" "L_3u3_6A_Bourns-SRP7028A"
			(at -4.81 4.65 90)
			(layer "F.Fab")
			(effects
				(font
					(size 0.7 0.7)
					(thickness 0.15)
				)
				(justify left bottom)
			)
		)
		(property "Datasheet" "https://www.bourns.com/docs/Product-Datasheets/SRP7028A.pdf"
			(at -0.003 -0.299 90)
			(layer "F.Fab")
			(effects
				(font
					(size 0.7 0.7)
					(thickness 0.15)
				)
				(justify left bottom)
			)
		)
		(property "Description" "Power Inductor (SMD), 3.3 µH, 6 A, Shielded, 12 A, SRP7028A Series"
			(at -0.003 -0.299 90)
			(layer "F.Fab")
			(effects
				(font
					(size 0.7 0.7)
					(thickness 0.15)
				)
				(justify left bottom)
			)
		)
		(property "Val" "3u3/6A"
			(at 0 0 90)
			(unlocked yes)
			(layer "F.Fab")
			(hide yes)
			(effects
				(font
					(size 1 1)
					(thickness 0.15)
				)
			)
		)
		(property "Manufacturer" "Bourns"
			(at 0 0 90)
			(unlocked yes)
			(layer "F.Fab")
			(hide yes)
			(effects
				(font
					(size 1 1)
					(thickness 0.15)
				)
			)
		)
		(property "MPN" "SRP7028A-3R3M"
			(at 0 0 90)
			(unlocked yes)
			(layer "F.Fab")
			(hide yes)
			(effects
				(font
					(size 1 1)
					(thickness 0.15)
				)
			)
		)
		(property "ISat" "12 A"
			(at 0 0 90)
			(unlocked yes)
			(layer "F.Fab")
			(hide yes)
			(effects
				(font
					(size 1 1)
					(thickness 0.15)
				)
			)
		)
		(property "IMax" "6 A"
			(at 0 0 90)
			(unlocked yes)
			(layer "F.Fab")
			(hide yes)
			(effects
				(font
					(size 1 1)
					(thickness 0.15)
				)
			)
		)
		(property "Size" "7.3x6.6x2.8"
			(at 0 0 90)
			(unlocked yes)
			(layer "F.Fab")
			(hide yes)
			(effects
				(font
					(size 1 1)
					(thickness 0.15)
				)
			)
		)
		(property "Author" "Antmicro"
			(at 0 0 90)
			(unlocked yes)
			(layer "F.Fab")
			(hide yes)
			(effects
				(font
					(size 1 1)
					(thickness 0.15)
				)
			)
		)
		(property "License" "Apache-2.0"
			(at 0 0 90)
			(unlocked yes)
			(layer "F.Fab")
			(hide yes)
			(effects
				(font
					(size 1 1)
					(thickness 0.15)
				)
			)
		)
		(sheetname "/DCDC/")
		(sheetfile "dcdc.kicad_sch")
		(attr smd)
		(fp_line
			(start 3.44 -3.39)
			(end -3.44 -3.39)
			(stroke
				(width 0.15)
				(type solid)
			)
			(layer "F.SilkS")
		)
		(fp_line
			(start 3.44 -2.115)
			(end 3.44 -3.39)
			(stroke
				(width 0.15)
				(type solid)
			)
			(layer "F.SilkS")
		)
		(fp_line
			(start -3.44 -2.115)
			(end -3.44 -3.39)
			(stroke
				(width 0.15)
				(type solid)
			)
			(layer "F.SilkS")
		)
		(fp_line
			(start 3.44 2.115)
			(end 3.44 3.39)
			(stroke
				(width 0.15)
				(type solid)
			)
			(layer "F.SilkS")
		)
		(fp_line
			(start -3.44 2.115)
			(end -3.44 3.39)
			(stroke
				(width 0.15)
				(type solid)
			)
			(layer "F.SilkS")
		)
		(fp_line
			(start -3.44 3.39)
			(end 3.44 3.39)
			(stroke
				(width 0.15)
				(type solid)
			)
			(layer "F.SilkS")
		)
		(fp_circle
			(center -4.39 0)
			(end -4.34 0)
			(stroke
				(width 0.15)
				(type solid)
			)
			(fill yes)
			(layer "F.SilkS")
		)
		(fp_rect
			(start -4.5 -3.6)
			(end 4.5 3.6)
			(stroke
				(width 0.05)
				(type solid)
			)
			(fill no)
			(layer "F.CrtYd")
		)
		(fp_text user "License: Apache-2.0"
			(at -4.81 8.25 90)
			(layer "F.Fab")
			(effects
				(font
					(size 0.7 0.7)
					(thickness 0.15)
				)
				(justify left bottom)
			)
		)
		(fp_text user "Author: Antmicro"
			(at -4.81 5.85 90)
			(layer "F.Fab")
			(effects
				(font
					(size 0.7 0.7)
					(thickness 0.15)
				)
				(justify left bottom)
			)
		)
		(fp_text user "${REFERENCE}"
			(at -4.81 7.05 90)
			(layer "F.Fab")
			(effects
				(font
					(size 0.7 0.7)
					(thickness 0.15)
				)
				(justify left bottom)
			)
		)
		(pad "1" smd roundrect
			(at -2.725 0 90)
			(size 2.95 3.5)
			(layers "F.Cu" "F.Mask" "F.Paste")
			(roundrect_rratio 0.05)
			(net 1297 "/DCDC/5V_{AON}_SW")
			(pintype "passive")
		)
		(pad "2" smd roundrect
			(at 2.725 0 90)
			(size 2.95 3.5)
			(layers "F.Cu" "F.Mask" "F.Paste")
			(roundrect_rratio 0.05)
			(net 1278 "/DCDC/5V_{AON}_OUT")
			(pintype "passive")
		)
	)
	(footprint "antmicro-footprints:SW_KMR211NGLFS_SMD"
		(layer "F.Cu")
		(at 215 55.52)
		(property "Reference" "S5"
			(at -3.5 2.85 180)
			(layer "F.SilkS")
			(hide yes)
			(effects
				(font
					(size 0.7 0.7)
					(thickness 0.15)
				)
				(justify left bottom)
			)
		)
		(property "Value" "SW_KMR211NGLFS_SMD"
			(at 0 2.8 0)
			(layer "F.Fab")
			(effects
				(font
					(size 0.7 0.7)
					(thickness 0.15)
				)
				(justify left bottom)
			)
		)
		(property "Datasheet" "http://www.farnell.com/datasheets/2631211.pdf"
			(at 0 0 0)
			(layer "F.Fab")
			(hide yes)
			(effects
				(font
					(size 1.27 1.27)
					(thickness 0.15)
				)
			)
		)
		(property "Description" "Tactile Switch, KMR 2 Series, Top Actuated, Surface Mount, Oval Button, 120 gf, 50mA at 32VDC"
			(at 0 0 0)
			(layer "F.Fab")
			(hide yes)
			(effects
				(font
					(size 1.27 1.27)
					(thickness 0.15)
				)
			)
		)
		(property "MPN" "KMR211NGLFS"
			(at 0 0 0)
			(unlocked yes)
			(layer "F.Fab")
			(hide yes)
			(effects
				(font
					(size 1 1)
					(thickness 0.15)
				)
			)
		)
		(property "Manufacturer" "C&K"
			(at 0 0 0)
			(unlocked yes)
			(layer "F.Fab")
			(hide yes)
			(effects
				(font
					(size 1 1)
					(thickness 0.15)
				)
			)
		)
		(property "Author" "Antmicro"
			(at 0 0 0)
			(unlocked yes)
			(layer "F.Fab")
			(hide yes)
			(effects
				(font
					(size 1 1)
					(thickness 0.15)
				)
			)
		)
		(property "License" "Apache-2.0"
			(at 0 0 0)
			(unlocked yes)
			(layer "F.Fab")
			(hide yes)
			(effects
				(font
					(size 1 1)
					(thickness 0.15)
				)
			)
		)
		(sheetname "/SoM_Power/")
		(sheetfile "som_power.kicad_sch")
		(attr smd)
		(fp_line
			(start -2.1 -1.6)
			(end -2.1 -1.499)
			(stroke
				(width 0.15)
				(type solid)
			)
			(layer "F.SilkS")
		)
		(fp_line
			(start -2.1 1.601)
			(end -2.1 1.48)
			(stroke
				(width 0.15)
				(type solid)
			)
			(layer "F.SilkS")
		)
		(fp_line
			(start 2.101 -1.6)
			(end -2.1 -1.6)
			(stroke
				(width 0.15)
				(type solid)
			)
			(layer "F.SilkS")
		)
		(fp_line
			(start 2.101 -1.58)
			(end 2.101 -1.459)
			(stroke
				(width 0.15)
				(type solid)
			)
			(layer "F.SilkS")
		)
		(fp_line
			(start 2.101 1.601)
			(end -2.1 1.601)
			(stroke
				(width 0.15)
				(type solid)
			)
			(layer "F.SilkS")
		)
		(fp_line
			(start 2.101 1.601)
			(end 2.101 1.48)
			(stroke
				(width 0.15)
				(type solid)
			)
			(layer "F.SilkS")
		)
		(fp_poly
			(pts
				(xy 2.751 1.75) (xy 2.751 -1.749) (xy -2.748 -1.749) (xy -2.748 1.749999)
			)
			(stroke
				(width 0.05)
				(type solid)
			)
			(fill no)
			(layer "F.CrtYd")
		)
		(fp_line
			(start -2.1 -1.6)
			(end -2.1 1.601)
			(stroke
				(width 0.15)
				(type solid)
			)
			(layer "F.Fab")
		)
		(fp_line
			(start -2.1 1.601)
			(end 2.101 1.601)
			(stroke
				(width 0.15)
				(type solid)
			)
			(layer "F.Fab")
		)
		(fp_line
			(start -0.248 -0.8)
			(end 0.25 -0.8)
			(stroke
				(width 0.15)
				(type solid)
			)
			(layer "F.Fab")
		)
		(fp_line
			(start 0.25 0.802)
			(end -0.248 0.802)
			(stroke
				(width 0.15)
				(type solid)
			)
			(layer "F.Fab")
		)
		(fp_line
			(start 2.101 -1.6)
			(end -2.1 -1.6)
			(stroke
				(width 0.15)
				(type solid)
			)
			(layer "F.Fab")
		)
		(fp_line
			(start 2.101 1.601)
			(end 2.101 -1.6)
			(stroke
				(width 0.15)
				(type solid)
			)
			(layer "F.Fab")
		)
		(fp_arc
			(start -0.248 0.802)
			(mid -1.050001 0.001)
			(end -0.248 -0.8)
			(stroke
				(width 0.15)
				(type solid)
			)
			(layer "F.Fab")
		)
		(fp_arc
			(start 0.25 -0.8)
			(mid 1.051001 0.001)
			(end 0.25 0.802)
			(stroke
				(width 0.15)
				(type solid)
			)
			(layer "F.Fab")
		)
		(fp_text user "Author: Antmicro"
			(at -3 5.5 0)
			(layer "F.Fab")
			(effects
				(font
					(size 0.7 0.7)
					(thickness 0.15)
				)
				(justify left bottom)
			)
		)
		(fp_text user "License: Apache-2.0"
			(at -3 6.75 0)
			(layer "F.Fab")
			(effects
				(font
					(size 0.7 0.7)
					(thickness 0.15)
				)
				(justify left bottom)
			)
		)
		(fp_text user "${REFERENCE}"
			(at -3 4.25 0)
			(layer "F.Fab")
			(effects
				(font
					(size 0.7 0.7)
					(thickness 0.15)
				)
				(justify left bottom)
			)
		)
		(pad "1" smd rect
			(at -2.048 -0.8 180)
			(size 0.9 1)
			(layers "F.Cu" "F.Mask" "F.Paste")
			(net 1 "GND")
			(pinfunction "1")
			(pintype "passive")
		)
		(pad "2" smd rect
			(at 2.049999 -0.8 180)
			(size 0.9 1)
			(layers "F.Cu" "F.Mask" "F.Paste")
			(net 1 "GND")
			(pinfunction "2")
			(pintype "passive")
		)
		(pad "3" smd rect
			(at -2.048 0.802 180)
			(size 0.9 1)
			(layers "F.Cu" "F.Mask" "F.Paste")
			(net 610 "/SoM_Power/~{PWR_BTN}")
			(pinfunction "3")
			(pintype "passive")
		)
		(pad "4" smd rect
			(at 2.05 0.802001 180)
			(size 0.9 1)
			(layers "F.Cu" "F.Mask" "F.Paste")
			(net 610 "/SoM_Power/~{PWR_BTN}")
			(pinfunction "4")
			(pintype "passive")
		)
	)
)
